(kicad_pcb
	(version 20260206)
	(generator "pcbnew")
	(generator_version "10.0")
	(general
		(thickness 1.6)
		(legacy_teardrops no)
	)
	(paper "A4")
	(title_block
		(title "timecard-production-celestica-r4006 — R4006-B0001-02_R01.brd")
		(comment 1 "Time Appliance Project (Time Card) / footprints 480-488 of 1113")
	)
	(layers
		(0 "F.Cu" signal "TOP")
		(4 "In1.Cu" signal "L02_GND1")
		(6 "In2.Cu" signal "L03_SIG1")
		(8 "In3.Cu" signal "L04_GND2")
		(10 "In4.Cu" signal "L05_VCC1")
		(12 "In5.Cu" signal "L06_VCC2")
		(14 "In6.Cu" signal "L07_GND3")
		(16 "In7.Cu" signal "L08_SIG2")
		(18 "In8.Cu" signal "L09_GND4")
		(2 "B.Cu" signal "BOTTOM")
		(9 "F.Adhes" user "F.Adhesive")
		(11 "B.Adhes" user "B.Adhesive")
		(13 "F.Paste" user "Package Geometry/Pastemask Top")
		(15 "B.Paste" user "Package Geometry/Pastemask Bottom")
		(5 "F.SilkS" user "Ref Des/Silkscreen Top")
		(7 "B.SilkS" user "Ref Des/Silkscreen Bottom")
		(1 "F.Mask" user "Board Geometry/Soldermask Top")
		(3 "B.Mask" user "Board Geometry/Soldermask Bottom")
		(17 "Dwgs.User" user "User.Drawings")
		(19 "Cmts.User" user "User.Comments")
		(21 "Eco1.User" user "User.Eco1")
		(23 "Eco2.User" user "User.Eco2")
		(25 "Edge.Cuts" user "Board Geometry/Outline")
		(27 "Margin" user)
		(31 "F.CrtYd" user "Package Geometry/Place Bound Top")
		(29 "B.CrtYd" user "Package Geometry/Place Bound Bottom")
		(35 "F.Fab" user "Ref Des/Assembly Top")
		(33 "B.Fab" user "Ref Des/Assembly Bottom")
	)
	(footprint ""
		(layer "F.Cu")
		(at 133.858 -20.828 180)
		(property "Reference" "R477"
			(at 0.127 5.29463 0)
			(unlocked yes)
			(layer "F.SilkS")
			(effects
				(font
					(size 0.7874 0.5842)
					(thickness 0.1524)
				)
			)
		)
		(property "Value" "VAL*"
			(at 0.02032 2.13233 180)
			(unlocked yes)
			(layer "F.Fab")
			(hide yes)
			(effects
				(font
					(size 0.7874 0.5842)
					(thickness 0.1524)
				)
			)
		)
		(property "Tolerance" "TOL*"
			(at 0.044704 3.05435 180)
			(unlocked yes)
			(layer "Cmts.User")
			(hide yes)
			(effects
				(font
					(size 0.7874 0.5842)
					(thickness 0.1524)
				)
			)
		)
		(property "User Part Number" "PARTNUM*"
			(at 0.02032 4.024884 180)
			(unlocked yes)
			(layer "Cmts.User")
			(hide yes)
			(effects
				(font
					(size 0.7874 0.5842)
					(thickness 0.1524)
				)
			)
		)
		(property "Device Type" "RESISTOR-G155-11003-01,100KOHMA"
			(at 0.008382 1.210564 180)
			(unlocked yes)
			(layer "F.Fab")
			(hide yes)
			(effects
				(font
					(size 0.7874 0.5842)
					(thickness 0.1524)
				)
			)
		)
		(duplicate_pad_numbers_are_jumpers no)
		(fp_line
			(start 1.143 0.5588)
			(end 1.143 -0.5588)
			(stroke
				(width 0.1)
				(type default)
			)
			(layer "F.SilkS")
		)
		(fp_line
			(start 1.143 -0.5588)
			(end -1.143 -0.5588)
			(stroke
				(width 0.1)
				(type default)
			)
			(layer "F.SilkS")
		)
		(fp_line
			(start -1.143 0.5588)
			(end 1.143 0.5588)
			(stroke
				(width 0.1)
				(type default)
			)
			(layer "F.SilkS")
		)
		(fp_line
			(start -1.143 -0.5588)
			(end -1.143 0.5588)
			(stroke
				(width 0.1)
				(type default)
			)
			(layer "F.SilkS")
		)
		(fp_poly
			(pts
				(xy -1.143 0.5588) (xy 1.143 0.5588) (xy 1.143 -0.5588) (xy -1.143 -0.5588)
			)
			(stroke
				(width 0)
				(type default)
			)
			(fill no)
			(layer "F.CrtYd")
		)
		(fp_line
			(start 0.508 0.3048)
			(end 0.508 -0.3048)
			(stroke
				(width 0.1)
				(type default)
			)
			(layer "F.Fab")
		)
		(fp_line
			(start 0.508 -0.3048)
			(end -0.508 -0.3048)
			(stroke
				(width 0.1)
				(type default)
			)
			(layer "F.Fab")
		)
		(fp_line
			(start -0.508 0.3048)
			(end 0.508 0.3048)
			(stroke
				(width 0.1)
				(type default)
			)
			(layer "F.Fab")
		)
		(fp_line
			(start -0.508 -0.3048)
			(end -0.508 0.3048)
			(stroke
				(width 0.1)
				(type default)
			)
			(layer "F.Fab")
		)
		(pad "1" smd rect
			(at -0.5334 0 180)
			(size 0.7112 0.6096)
			(layers "F.Cu" "F.Mask" "F.Paste")
			(net "XP3R3V_FPGA")
		)
		(pad "2" smd rect
			(at 0.5334 0 180)
			(size 0.7112 0.6096)
			(layers "F.Cu" "F.Mask" "F.Paste")
			(net "FPGA_EEPROM_I2C_SCL")
		)
		(zone
			(layer "F.Cu")
			(hatch none 0.5)
			(connect_pads
				(clearance 0)
			)
			(min_thickness 0.25)
			(keepout
				(tracks allowed)
				(vias not_allowed)
				(pads allowed)
				(copperpour not_allowed)
				(footprints allowed)
			)
			(placement
				(enabled no)
				(sheetname "")
			)
			(fill
				(thermal_gap 0.5)
				(thermal_bridge_width 0.5)
				(island_removal_mode 0)
			)
			(polygon
				(pts
					(xy 133.9342 -21.1328) (xy 133.7818 -21.1328) (xy 133.7818 -20.5232) (xy 133.9342 -20.5232)
				)
			)
		)
		(zone
			(layer "F.Cu")
			(hatch none 0.5)
			(connect_pads
				(clearance 0)
			)
			(min_thickness 0.25)
			(keepout
				(tracks not_allowed)
				(vias allowed)
				(pads allowed)
				(copperpour not_allowed)
				(footprints allowed)
			)
			(placement
				(enabled no)
				(sheetname "")
			)
			(fill
				(thermal_gap 0.5)
				(thermal_bridge_width 0.5)
				(island_removal_mode 0)
			)
			(polygon
				(pts
					(xy 133.9342 -21.1328) (xy 133.7818 -21.1328) (xy 133.7818 -20.5232) (xy 133.9342 -20.5232)
				)
			)
		)
	)
	(footprint ""
		(layer "F.Cu")
		(at 92.372942 -61.0108 90)
		(property "Reference" "C51"
			(at -2.95275 0.337058 0)
			(unlocked yes)
			(layer "F.SilkS")
			(effects
				(font
					(size 0.635 0.4064)
					(thickness 0.1524)
				)
			)
		)
		(property "Value" "VAL*"
			(at 0.193548 2.13614 90)
			(unlocked yes)
			(layer "F.Fab")
			(hide yes)
			(effects
				(font
					(size 0.7874 0.5842)
					(thickness 0.1524)
				)
			)
		)
		(property "Tolerance" "TOL*"
			(at 0.216154 3.1496 90)
			(unlocked yes)
			(layer "Cmts.User")
			(hide yes)
			(effects
				(font
					(size 0.7874 0.5842)
					(thickness 0.1524)
				)
			)
		)
		(property "Device Type" "CAPACITOR-G104-0A120-FJ,12PF,5%"
			(at 0.184404 1.180592 90)
			(unlocked yes)
			(layer "F.Fab")
			(hide yes)
			(effects
				(font
					(size 0.7874 0.5842)
					(thickness 0.1524)
				)
			)
		)
		(property "User Part Number" "PARTNUM*"
			(at 0.216154 4.185666 90)
			(unlocked yes)
			(layer "Cmts.User")
			(hide yes)
			(effects
				(font
					(size 0.7874 0.5842)
					(thickness 0.1524)
				)
			)
		)
		(duplicate_pad_numbers_are_jumpers no)
		(fp_line
			(start 0.671322 -0.4445)
			(end 0.671322 0.4445)
			(stroke
				(width 0.1)
				(type default)
			)
			(layer "F.SilkS")
		)
		(fp_line
			(start -0.671322 -0.4445)
			(end 0.671322 -0.4445)
			(stroke
				(width 0.1)
				(type default)
			)
			(layer "F.SilkS")
		)
		(fp_line
			(start 0.671322 0.4445)
			(end -0.671322 0.4445)
			(stroke
				(width 0.1)
				(type default)
			)
			(layer "F.SilkS")
		)
		(fp_line
			(start -0.671322 0.4445)
			(end -0.671322 -0.4445)
			(stroke
				(width 0.1)
				(type default)
			)
			(layer "F.SilkS")
		)
		(fp_rect
			(start -0.671322 -0.4445)
			(end 0.671322 0.4445)
			(stroke
				(width 0)
				(type default)
			)
			(fill no)
			(layer "F.CrtYd")
		)
		(fp_line
			(start 0.31496 -0.1651)
			(end -0.31496 -0.1651)
			(stroke
				(width 0.1)
				(type default)
			)
			(layer "F.Fab")
		)
		(fp_line
			(start -0.31496 -0.1651)
			(end -0.31496 0.1651)
			(stroke
				(width 0.1)
				(type default)
			)
			(layer "F.Fab")
		)
		(fp_line
			(start 0.31496 0.1651)
			(end 0.31496 -0.1651)
			(stroke
				(width 0.1)
				(type default)
			)
			(layer "F.Fab")
		)
		(fp_line
			(start -0.31496 0.1651)
			(end 0.31496 0.1651)
			(stroke
				(width 0.1)
				(type default)
			)
			(layer "F.Fab")
		)
		(pad "1" smd rect
			(at -0.264922 0 90)
			(size 0.3048 0.381)
			(layers "F.Cu" "F.Mask" "F.Paste")
			(net "UNNAMED_9_CAPACITOR_I17_1")
		)
		(pad "2" smd rect
			(at 0.264922 0 90)
			(size 0.3048 0.381)
			(layers "F.Cu" "F.Mask" "F.Paste")
			(net "SG")
		)
		(zone
			(layer "F.Cu")
			(hatch none 0.5)
			(connect_pads
				(clearance 0)
			)
			(min_thickness 0.25)
			(keepout
				(tracks allowed)
				(vias not_allowed)
				(pads allowed)
				(copperpour not_allowed)
				(footprints allowed)
			)
			(placement
				(enabled no)
				(sheetname "")
			)
			(fill
				(thermal_gap 0.5)
				(thermal_bridge_width 0.5)
				(island_removal_mode 0)
			)
			(polygon
				(pts
					(xy 92.182442 -60.898278) (xy 92.563442 -60.898278) (xy 92.563442 -61.123322) (xy 92.182442 -61.123322)
				)
			)
		)
	)
	(footprint ""
		(layer "F.Cu")
		(at 85.598 -87.376)
		(property "Reference" "TP21"
			(at -1.2192 -1.61163 0)
			(unlocked yes)
			(layer "F.SilkS")
			(effects
				(font
					(size 0.7874 0.5842)
					(thickness 0.1524)
				)
				(justify left)
			)
		)
		(property "Value" ""
			(at 0 0 0)
			(layer "F.Fab")
			(effects
				(font
					(size 1.27 1.27)
				)
			)
		)
		(property "Device Type" "TP_PIONT-TP010CT020B030_PTH-TPA"
			(at -1.341882 0.996696 0)
			(unlocked yes)
			(layer "F.Fab")
			(hide yes)
			(effects
				(font
					(size 0.7874 0.5842)
					(thickness 0.000001)
				)
				(justify left)
			)
		)
		(duplicate_pad_numbers_are_jumpers no)
		(fp_poly
			(pts
				(arc
					(start 0.889 0)
					(mid -0.889 0)
					(end 0.889 0)
				)
			)
			(stroke
				(width 0)
				(type default)
			)
			(fill no)
			(layer "B.CrtYd")
		)
		(fp_poly
			(pts
				(arc
					(start 0.889 0)
					(mid -0.889 0)
					(end 0.889 0)
				)
			)
			(stroke
				(width 0)
				(type default)
			)
			(fill no)
			(layer "F.CrtYd")
		)
		(pad "1" thru_hole circle
			(at 0 0)
			(size 0.508 0.508)
			(drill 0.254)
			(layers "*.Cu" "*.Mask")
			(remove_unused_layers no)
			(net "PCA9546_RST_N")
			(clearance 0.1016)
			(padstack
				(mode front_inner_back)
				(layer "Inner"
					(shape circle)
					(size 0.508 0.508)
					(clearance 0.1016)
				)
				(layer "B.Cu"
					(shape circle)
					(size 0.762 0.762)
					(clearance -0.0254)
				)
			)
		)
	)
	(footprint ""
		(layer "F.Cu")
		(at 57.277 -130.048)
		(property "Reference" "SP59"
			(at 0 0 0)
			(layer "F.SilkS")
			(hide yes)
			(effects
				(font
					(size 1.27 1.27)
				)
			)
		)
		(property "Value" ""
			(at 0 0 0)
			(layer "F.Fab")
			(effects
				(font
					(size 1.27 1.27)
				)
			)
		)
		(duplicate_pad_numbers_are_jumpers no)
	)
	(footprint ""
		(layer "F.Cu")
		(at 42.545 -123.19)
		(property "Reference" "SP22"
			(at 0 0 0)
			(layer "F.SilkS")
			(hide yes)
			(effects
				(font
					(size 1.27 1.27)
				)
			)
		)
		(property "Value" ""
			(at 0 0 0)
			(layer "F.Fab")
			(effects
				(font
					(size 1.27 1.27)
				)
			)
		)
		(duplicate_pad_numbers_are_jumpers no)
	)
	(footprint ""
		(layer "F.Cu")
		(at 141.732 -99.441)
		(property "Reference" "R14"
			(at 2.032 0.92075 0)
			(unlocked yes)
			(layer "F.SilkS")
			(effects
				(font
					(size 0.635 0.4064)
					(thickness 0.1524)
				)
			)
		)
		(property "Value" "VAL*"
			(at 0.0508 2.245106 0)
			(unlocked yes)
			(layer "F.Fab")
			(hide yes)
			(effects
				(font
					(size 0.7874 0.5842)
					(thickness 0.1524)
				)
			)
		)
		(property "Tolerance" "TOL*"
			(at 0.0508 3.261106 0)
			(unlocked yes)
			(layer "Cmts.User")
			(hide yes)
			(effects
				(font
					(size 0.7874 0.5842)
					(thickness 0.1524)
				)
			)
		)
		(property "Device Type" "RESISTOR-G155-03921-01,3.92KOHA"
			(at 0.0762 1.254506 0)
			(unlocked yes)
			(layer "F.Fab")
			(hide yes)
			(effects
				(font
					(size 0.7874 0.5842)
					(thickness 0.1524)
				)
			)
		)
		(property "User Part Number" "PARTNUM*"
			(at 0.0762 4.302506 0)
			(unlocked yes)
			(layer "Cmts.User")
			(hide yes)
			(effects
				(font
					(size 0.7874 0.5842)
					(thickness 0.1524)
				)
			)
		)
		(duplicate_pad_numbers_are_jumpers no)
		(fp_line
			(start -1.143 -0.5588)
			(end -1.143 0.5588)
			(stroke
				(width 0.1)
				(type default)
			)
			(layer "F.SilkS")
		)
		(fp_line
			(start -1.143 0.5588)
			(end 1.143 0.5588)
			(stroke
				(width 0.1)
				(type default)
			)
			(layer "F.SilkS")
		)
		(fp_line
			(start 1.143 -0.5588)
			(end -1.143 -0.5588)
			(stroke
				(width 0.1)
				(type default)
			)
			(layer "F.SilkS")
		)
		(fp_line
			(start 1.143 0.5588)
			(end 1.143 -0.5588)
			(stroke
				(width 0.1)
				(type default)
			)
			(layer "F.SilkS")
		)
		(fp_rect
			(start 1.143 -0.5588)
			(end -1.143 0.5588)
			(stroke
				(width 0)
				(type default)
			)
			(fill no)
			(layer "F.CrtYd")
		)
		(fp_line
			(start -0.508 -0.3048)
			(end -0.508 0.3048)
			(stroke
				(width 0.1)
				(type default)
			)
			(layer "F.Fab")
		)
		(fp_line
			(start -0.508 0.3048)
			(end 0.508 0.3048)
			(stroke
				(width 0.1)
				(type default)
			)
			(layer "F.Fab")
		)
		(fp_line
			(start 0.508 -0.3048)
			(end -0.508 -0.3048)
			(stroke
				(width 0.1)
				(type default)
			)
			(layer "F.Fab")
		)
		(fp_line
			(start 0.508 0.3048)
			(end 0.508 -0.3048)
			(stroke
				(width 0.1)
				(type default)
			)
			(layer "F.Fab")
		)
		(pad "1" smd rect
			(at -0.5334 0)
			(size 0.7112 0.6096)
			(layers "F.Cu" "F.Mask" "F.Paste")
			(net "XP12R0V_A_PG")
		)
		(pad "2" smd rect
			(at 0.5334 0)
			(size 0.7112 0.6096)
			(layers "F.Cu" "F.Mask" "F.Paste")
			(net "SG")
		)
		(zone
			(layer "F.Cu")
			(hatch none 0.5)
			(connect_pads
				(clearance 0)
			)
			(min_thickness 0.25)
			(keepout
				(tracks allowed)
				(vias not_allowed)
				(pads allowed)
				(copperpour not_allowed)
				(footprints allowed)
			)
			(placement
				(enabled no)
				(sheetname "")
			)
			(fill
				(thermal_gap 0.5)
				(thermal_bridge_width 0.5)
				(island_removal_mode 0)
			)
			(polygon
				(pts
					(xy 141.8082 -99.7458) (xy 141.6558 -99.7458) (xy 141.6558 -99.1362) (xy 141.8082 -99.1362)
				)
			)
		)
	)
	(footprint ""
		(layer "F.Cu")
		(at 115.062 -29.464 -90)
		(property "Reference" "R439"
			(at 2.794 -1.18237 90)
			(unlocked yes)
			(layer "F.SilkS")
			(effects
				(font
					(size 0.7874 0.5842)
					(thickness 0.1524)
				)
			)
		)
		(property "Value" "VAL*"
			(at 0.02032 2.13233 270)
			(unlocked yes)
			(layer "F.Fab")
			(hide yes)
			(effects
				(font
					(size 0.7874 0.5842)
					(thickness 0.1524)
				)
			)
		)
		(property "Tolerance" "TOL*"
			(at 0.044704 3.05435 270)
			(unlocked yes)
			(layer "Cmts.User")
			(hide yes)
			(effects
				(font
					(size 0.7874 0.5842)
					(thickness 0.1524)
				)
			)
		)
		(property "User Part Number" "PARTNUM*"
			(at 0.02032 4.024884 270)
			(unlocked yes)
			(layer "Cmts.User")
			(hide yes)
			(effects
				(font
					(size 0.7874 0.5842)
					(thickness 0.1524)
				)
			)
		)
		(property "Device Type" "RESISTOR-G155-11002-01,10KOHM,A"
			(at 0.008382 1.210564 270)
			(unlocked yes)
			(layer "F.Fab")
			(hide yes)
			(effects
				(font
					(size 0.7874 0.5842)
					(thickness 0.1524)
				)
			)
		)
		(duplicate_pad_numbers_are_jumpers no)
		(fp_line
			(start -1.143 0.5588)
			(end 1.143 0.5588)
			(stroke
				(width 0.1)
				(type default)
			)
			(layer "F.SilkS")
		)
		(fp_line
			(start 1.143 0.5588)
			(end 1.143 -0.5588)
			(stroke
				(width 0.1)
				(type default)
			)
			(layer "F.SilkS")
		)
		(fp_line
			(start -1.143 -0.5588)
			(end -1.143 0.5588)
			(stroke
				(width 0.1)
				(type default)
			)
			(layer "F.SilkS")
		)
		(fp_line
			(start 1.143 -0.5588)
			(end -1.143 -0.5588)
			(stroke
				(width 0.1)
				(type default)
			)
			(layer "F.SilkS")
		)
		(fp_poly
			(pts
				(xy -1.143 0.5588) (xy 1.143 0.5588) (xy 1.143 -0.5588) (xy -1.143 -0.5588)
			)
			(stroke
				(width 0)
				(type default)
			)
			(fill no)
			(layer "F.CrtYd")
		)
		(fp_line
			(start -0.508 0.3048)
			(end 0.508 0.3048)
			(stroke
				(width 0.1)
				(type default)
			)
			(layer "F.Fab")
		)
		(fp_line
			(start 0.508 0.3048)
			(end 0.508 -0.3048)
			(stroke
				(width 0.1)
				(type default)
			)
			(layer "F.Fab")
		)
		(fp_line
			(start -0.508 -0.3048)
			(end -0.508 0.3048)
			(stroke
				(width 0.1)
				(type default)
			)
			(layer "F.Fab")
		)
		(fp_line
			(start 0.508 -0.3048)
			(end -0.508 -0.3048)
			(stroke
				(width 0.1)
				(type default)
			)
			(layer "F.Fab")
		)
		(pad "1" smd rect
			(at -0.5334 0 270)
			(size 0.7112 0.6096)
			(layers "F.Cu" "F.Mask" "F.Paste")
			(net "FPGA_IN_MAC_PPS_OUTP")
		)
		(pad "2" smd rect
			(at 0.5334 0 270)
			(size 0.7112 0.6096)
			(layers "F.Cu" "F.Mask" "F.Paste")
			(net "XP2R5V_FPGA")
		)
		(zone
			(layer "F.Cu")
			(hatch none 0.5)
			(connect_pads
				(clearance 0)
			)
			(min_thickness 0.25)
			(keepout
				(tracks allowed)
				(vias not_allowed)
				(pads allowed)
				(copperpour not_allowed)
				(footprints allowed)
			)
			(placement
				(enabled no)
				(sheetname "")
			)
			(fill
				(thermal_gap 0.5)
				(thermal_bridge_width 0.5)
				(island_removal_mode 0)
			)
			(polygon
				(pts
					(xy 114.7572 -29.5402) (xy 114.7572 -29.3878) (xy 115.3668 -29.3878) (xy 115.3668 -29.5402)
				)
			)
		)
		(zone
			(layer "F.Cu")
			(hatch none 0.5)
			(connect_pads
				(clearance 0)
			)
			(min_thickness 0.25)
			(keepout
				(tracks not_allowed)
				(vias allowed)
				(pads allowed)
				(copperpour not_allowed)
				(footprints allowed)
			)
			(placement
				(enabled no)
				(sheetname "")
			)
			(fill
				(thermal_gap 0.5)
				(thermal_bridge_width 0.5)
				(island_removal_mode 0)
			)
			(polygon
				(pts
					(xy 114.7572 -29.5402) (xy 114.7572 -29.3878) (xy 115.3668 -29.3878) (xy 115.3668 -29.5402)
				)
			)
		)
	)
	(footprint ""
		(layer "F.Cu")
		(at 60.452 -123.952)
		(property "Reference" "SP29"
			(at 0 0 0)
			(layer "F.SilkS")
			(hide yes)
			(effects
				(font
					(size 1.27 1.27)
				)
			)
		)
		(property "Value" ""
			(at 0 0 0)
			(layer "F.Fab")
			(effects
				(font
					(size 1.27 1.27)
				)
			)
		)
		(duplicate_pad_numbers_are_jumpers no)
	)
	(footprint ""
		(layer "F.Cu")
		(at 147.32 -26.6192)
		(property "Reference" "TP22"
			(at -1.7272 -0.77343 0)
			(unlocked yes)
			(layer "F.SilkS")
			(effects
				(font
					(size 0.7874 0.5842)
					(thickness 0.1524)
				)
				(justify left)
			)
		)
		(property "Value" ""
			(at 0 0 0)
			(layer "F.Fab")
			(effects
				(font
					(size 1.27 1.27)
				)
			)
		)
		(property "Device Type" "TP_PIONT-TP010CT020B030_PTH-TPA"
			(at -1.341882 0.996696 0)
			(unlocked yes)
			(layer "F.Fab")
			(hide yes)
			(effects
				(font
					(size 0.7874 0.5842)
					(thickness 0.000001)
				)
				(justify left)
			)
		)
		(duplicate_pad_numbers_are_jumpers no)
		(fp_poly
			(pts
				(arc
					(start 0.889 0)
					(mid -0.889 0)
					(end 0.889 0)
				)
			)
			(stroke
				(width 0)
				(type default)
			)
			(fill no)
			(layer "B.CrtYd")
		)
		(fp_poly
			(pts
				(arc
					(start 0.889 0)
					(mid -0.889 0)
					(end 0.889 0)
				)
			)
			(stroke
				(width 0)
				(type default)
			)
			(fill no)
			(layer "F.CrtYd")
		)
		(pad "1" thru_hole circle
			(at 0 0)
			(size 0.508 0.508)
			(drill 0.254)
			(layers "*.Cu" "*.Mask")
			(remove_unused_layers no)
			(net "FPGA_IN_LM75B_INT3_N")
			(clearance 0.1016)
			(padstack
				(mode front_inner_back)
				(layer "Inner"
					(shape circle)
					(size 0.508 0.508)
					(clearance 0.1016)
				)
				(layer "B.Cu"
					(shape circle)
					(size 0.762 0.762)
					(clearance -0.0254)
				)
			)
		)
	)
)
